FILE_TYPE = CONNECTIVITY;
{Allegro Design Entry HDL 16.6-p007 (v16-6-112F) 10/10/2012}
"PAGE_NUMBER" = 81;
0"NC";
1"M_J_DQS_DP<17:0>";
2"M_J_DQS_DN<17:0>";
3"M_J_DQ<63:0>";
4"M_J_MA<17:0>";
5"M_J_CLK_DP<3:0>";
6"M_J_CLK_DN<3:0>";
7"M_J_CS_N<7:0>";
8"M_J_BG<1:0>";
9"M_J_BA<1:0>";
10"M_J_ECC<7:0>";
11"M_J_CKE<3:0>";
12"M_J_ODT<3:0>";
13"PVDDQ_GHJ\g";
14"GND\g";
15"GND\g";
16"GND\g";
17"PVPP_GHJ\g";
18"PVTT_GHJ\g";
19"PVPP_GHJ\g";
20"P12V_NVDIMM_GHJ\g";
21"GND\g";
22"M_J_DQS_DP<3>";
23"M_J_VREF";
24"M_J_DQS_DN<9>";
25"M_J_DQS_DP<8>";
26"M_J_DQS_DN<8>";
27"M_J_DQ<24>";
28"M_J_ACT_N";
29"FM_DIMM_EVENT_COD_N";
30"TP_CH_J_DIMM_J0_RFU_1";
31"TP_CH_J_DIMM_J0_RFU_0";
32"TP_CH_J_DIMM_J0_RFU_2";
33"SMB_DDR_GHJ_VPP_SCL";
34"SMB_DDR_GHJ_VPP_SDA";
35"FM_ADR_COMPLETE_GHJ_N";
36"M_GHJ_RST_N";
37"M_J_PAR";
38"M_J_C<2>";
39"M_J_CS_N<0>";
40"M_J_CKE<0>";
41"M_J_ODT<1>";
42"M_J_ODT<0>";
43"M_J_ECC<6>";
44"M_J_MA<2>";
45"M_J_BG<0>";
46"M_J_CKE<1>";
47"M_J_ECC<1>";
48"M_J_ECC<0>";
49"M_J_ECC<3>";
50"M_J_ECC<2>";
51"M_J_ECC<5>";
52"M_J_ECC<4>";
53"M_J_ECC<7>";
54"M_J_MA<1>";
55"M_J_MA<0>";
56"M_J_CS_N<1>";
57"M_J_BA<1>";
58"M_J_BA<0>";
59"M_J_BG<1>";
60"M_J_CS_N<2>";
61"M_J_CS_N<3>";
62"M_J_CLK_DN<0>";
63"M_J_CLK_DP<0>";
64"M_J_CLK_DN<1>";
65"M_J_CLK_DP<1>";
66"M_J_ALERT_N";
67"M_J_DQ<4>";
68"M_J_DQ<5>";
69"M_J_DQ<2>";
70"M_J_DQ<3>";
71"M_J_DQ<46>";
72"M_J_DQ<49>";
73"M_J_DQ<14>";
74"M_J_DQ<27>";
75"M_J_DQ<26>";
76"M_J_DQ<39>";
77"M_J_DQ<37>";
78"M_J_DQ<34>";
79"M_J_DQ<1>";
80"M_J_DQ<0>";
81"M_J_DQ<7>";
82"M_J_DQ<6>";
83"M_J_DQ<9>";
84"M_J_DQ<8>";
85"M_J_DQ<10>";
86"M_J_DQ<13>";
87"M_J_DQ<12>";
88"M_J_DQ<15>";
89"M_J_DQ<17>";
90"M_J_DQ<19>";
91"M_J_DQ<18>";
92"M_J_DQ<21>";
93"M_J_DQ<20>";
94"M_J_DQ<23>";
95"M_J_DQ<22>";
96"M_J_DQ<25>";
97"M_J_DQ<31>";
98"M_J_DQ<30>";
99"M_J_DQ<33>";
100"M_J_DQ<32>";
101"M_J_DQ<35>";
102"M_J_DQ<36>";
103"M_J_DQ<38>";
104"M_J_DQ<41>";
105"M_J_DQ<40>";
106"M_J_DQ<43>";
107"M_J_DQ<42>";
108"M_J_DQ<45>";
109"M_J_DQ<44>";
110"M_J_DQ<47>";
111"M_J_DQ<29>";
112"M_J_DQ<28>";
113"M_J_DQ<11>";
114"M_J_DQ<16>";
115"M_J_MA<16>";
116"M_J_MA<15>";
117"M_J_MA<14>";
118"M_J_MA<11>";
119"M_J_MA<10>";
120"M_J_MA<9>";
121"M_J_MA<8>";
122"M_J_MA<7>";
123"M_J_MA<6>";
124"M_J_MA<5>";
125"M_J_MA<4>";
126"M_J_MA<3>";
127"M_J_MA<17>";
128"M_J_MA<13>";
129"M_J_MA<12>";
130"M_J_DQ<62>";
131"M_J_DQ<63>";
132"M_J_DQ<60>";
133"M_J_DQ<48>";
134"M_J_DQ<51>";
135"M_J_DQ<50>";
136"M_J_DQ<53>";
137"M_J_DQ<52>";
138"M_J_DQ<55>";
139"M_J_DQ<59>";
140"M_J_DQ<56>";
141"M_J_DQ<54>";
142"M_J_DQ<57>";
143"M_J_DQ<58>";
144"M_J_DQ<61>";
145"M_J_DQS_DP<6>";
146"M_J_DQS_DN<6>";
147"M_J_DQS_DP<5>";
148"M_J_DQS_DN<5>";
149"M_J_DQS_DP<4>";
150"M_J_DQS_DN<4>";
151"M_J_DQS_DN<3>";
152"M_J_DQS_DP<2>";
153"M_J_DQS_DN<2>";
154"M_J_DQS_DP<1>";
155"M_J_DQS_DN<1>";
156"M_J_DQS_DP<0>";
157"M_J_DQS_DN<0>";
158"M_J_DQS_DP<9>";
159"M_J_DQS_DP<7>";
160"M_J_DQS_DN<7>";
161"M_J_DQS_DN<17>";
162"M_J_DQS_DP<16>";
163"M_J_DQS_DN<16>";
164"M_J_DQS_DP<15>";
165"M_J_DQS_DN<15>";
166"M_J_DQS_DP<14>";
167"M_J_DQS_DN<14>";
168"M_J_DQS_DP<13>";
169"M_J_DQS_DN<13>";
170"M_J_DQS_DP<12>";
171"M_J_DQS_DN<12>";
172"M_J_DQS_DP<11>";
173"M_J_DQS_DN<11>";
174"M_J_DQS_DP<10>";
175"M_J_DQS_DN<10>";
176"M_J_DQS_DP<17>";
%"TAP"
"6","(850,4700)","2","mstr_standard","I10";
;
CDS_LIB"mstr_standard"
BODY_TYPE"PLUMBING"
HDL_TAP"TRUE";
"B \NAC \NWC"2;
"S \NAC"
BN"13"169;
%"TAP"
"6","(-1800,2150)","2","mstr_standard","I100";
;
CDS_LIB"mstr_standard"
BODY_TYPE"PLUMBING"
HDL_TAP"TRUE";
"B \NAC \NWC"3;
"S \NAC"
BN"11"113;
%"TAP"
"6","(-1800,2100)","2","mstr_standard","I101";
;
CDS_LIB"mstr_standard"
BODY_TYPE"PLUMBING"
HDL_TAP"TRUE";
"B \NAC \NWC"3;
"S \NAC"
BN"8"84;
%"TAP"
"6","(-1800,2050)","2","mstr_standard","I102";
;
CDS_LIB"mstr_standard"
BODY_TYPE"PLUMBING"
HDL_TAP"TRUE";
"B \NAC \NWC"3;
"S \NAC"
BN"9"83;
%"TAP"
"6","(-1800,2000)","2","mstr_standard","I103";
;
CDS_LIB"mstr_standard"
BODY_TYPE"PLUMBING"
HDL_TAP"TRUE";
"B \NAC \NWC"3;
"S \NAC"
BN"6"82;
%"TAP"
"6","(-1800,1750)","2","mstr_standard","I104";
;
CDS_LIB"mstr_standard"
BODY_TYPE"PLUMBING"
HDL_TAP"TRUE";
"B \NAC \NWC"3;
"S \NAC"
BN"3"70;
%"TAP"
"6","(-1800,1850)","2","mstr_standard","I105";
;
CDS_LIB"mstr_standard"
BODY_TYPE"PLUMBING"
HDL_TAP"TRUE";
"B \NAC \NWC"3;
"S \NAC"
BN"5"68;
%"TAP"
"6","(-1800,1800)","2","mstr_standard","I106";
;
CDS_LIB"mstr_standard"
BODY_TYPE"PLUMBING"
HDL_TAP"TRUE";
"B \NAC \NWC"3;
"S \NAC"
BN"2"69;
%"TAP"
"6","(-1800,1950)","2","mstr_standard","I107";
;
CDS_LIB"mstr_standard"
BODY_TYPE"PLUMBING"
HDL_TAP"TRUE";
"B \NAC \NWC"3;
"S \NAC"
BN"7"81;
%"TAP"
"6","(-1800,1900)","2","mstr_standard","I108";
;
CDS_LIB"mstr_standard"
BODY_TYPE"PLUMBING"
HDL_TAP"TRUE";
"B \NAC \NWC"3;
"S \NAC"
BN"4"67;
%"TAP"
"6","(-1800,1700)","2","mstr_standard","I109";
;
CDS_LIB"mstr_standard"
BODY_TYPE"PLUMBING"
HDL_TAP"TRUE";
"B \NAC \NWC"3;
"S \NAC"
BN"0"80;
%"TAP"
"6","(850,4500)","2","mstr_standard","I11";
;
CDS_LIB"mstr_standard"
BODY_TYPE"PLUMBING"
HDL_TAP"TRUE";
"B \NAC \NWC"2;
"S \NAC"
BN"11"173;
%"TAP"
"6","(-1800,1650)","2","mstr_standard","I110";
;
CDS_LIB"mstr_standard"
BODY_TYPE"PLUMBING"
HDL_TAP"TRUE";
"B \NAC \NWC"3;
"S \NAC"
BN"1"79;
%"TAP"
"6","(-3300,4800)","0","mstr_standard","I112";
;
CDS_LIB"mstr_standard"
BODY_TYPE"PLUMBING"
HDL_TAP"TRUE";
"B \NAC \NWC"4;
"S \NAC"
BN"17"127;
%"TAP"
"6","(-3300,4750)","0","mstr_standard","I114";
;
CDS_LIB"mstr_standard"
BODY_TYPE"PLUMBING"
HDL_TAP"TRUE";
"B \NAC \NWC"4;
"S \NAC"
BN"16"115;
%"TAP"
"6","(-3300,4700)","0","mstr_standard","I115";
;
CDS_LIB"mstr_standard"
BODY_TYPE"PLUMBING"
HDL_TAP"TRUE";
"B \NAC \NWC"4;
"S \NAC"
BN"15"116;
%"TAP"
"6","(-3300,4650)","0","mstr_standard","I116";
;
CDS_LIB"mstr_standard"
BODY_TYPE"PLUMBING"
HDL_TAP"TRUE";
"B \NAC \NWC"4;
"S \NAC"
BN"14"117;
%"TAP"
"6","(-3300,4600)","0","mstr_standard","I117";
;
CDS_LIB"mstr_standard"
BODY_TYPE"PLUMBING"
HDL_TAP"TRUE";
"B \NAC \NWC"4;
"S \NAC"
BN"13"128;
%"TAP"
"6","(-3300,4550)","0","mstr_standard","I118";
;
CDS_LIB"mstr_standard"
BODY_TYPE"PLUMBING"
HDL_TAP"TRUE";
"B \NAC \NWC"4;
"S \NAC"
BN"12"129;
%"TAP"
"6","(-3300,4500)","0","mstr_standard","I119";
;
CDS_LIB"mstr_standard"
BODY_TYPE"PLUMBING"
HDL_TAP"TRUE";
"B \NAC \NWC"4;
"S \NAC"
BN"11"118;
%"TAP"
"6","(650,4750)","2","mstr_standard","I12";
;
CDS_LIB"mstr_standard"
BODY_TYPE"PLUMBING"
HDL_TAP"TRUE";
"B \NAC \NWC"1;
"S \NAC"
BN"13"168;
%"TAP"
"6","(-3300,4450)","0","mstr_standard","I120";
;
CDS_LIB"mstr_standard"
BODY_TYPE"PLUMBING"
HDL_TAP"TRUE";
"B \NAC \NWC"4;
"S \NAC"
BN"10"119;
%"TAP"
"6","(-3300,4400)","0","mstr_standard","I121";
;
CDS_LIB"mstr_standard"
BODY_TYPE"PLUMBING"
HDL_TAP"TRUE";
"B \NAC \NWC"4;
"S \NAC"
BN"9"120;
%"TAP"
"6","(-3300,4350)","0","mstr_standard","I122";
;
CDS_LIB"mstr_standard"
BODY_TYPE"PLUMBING"
HDL_TAP"TRUE";
"B \NAC \NWC"4;
"S \NAC"
BN"8"121;
%"TAP"
"6","(-3300,4300)","0","mstr_standard","I123";
;
CDS_LIB"mstr_standard"
BODY_TYPE"PLUMBING"
HDL_TAP"TRUE";
"B \NAC \NWC"4;
"S \NAC"
BN"7"122;
%"TAP"
"6","(-3300,4250)","0","mstr_standard","I124";
;
CDS_LIB"mstr_standard"
BODY_TYPE"PLUMBING"
HDL_TAP"TRUE";
"B \NAC \NWC"4;
"S \NAC"
BN"6"123;
%"TAP"
"6","(-3300,4200)","0","mstr_standard","I125";
;
CDS_LIB"mstr_standard"
BODY_TYPE"PLUMBING"
HDL_TAP"TRUE";
"B \NAC \NWC"4;
"S \NAC"
BN"5"124;
%"TAP"
"6","(-3300,4150)","0","mstr_standard","I126";
;
CDS_LIB"mstr_standard"
BODY_TYPE"PLUMBING"
HDL_TAP"TRUE";
"B \NAC \NWC"4;
"S \NAC"
BN"4"125;
%"TAP"
"6","(-3300,4100)","0","mstr_standard","I127";
;
CDS_LIB"mstr_standard"
BODY_TYPE"PLUMBING"
HDL_TAP"TRUE";
"B \NAC \NWC"4;
"S \NAC"
BN"3"126;
%"TAP"
"6","(-3300,4050)","0","mstr_standard","I128";
;
CDS_LIB"mstr_standard"
BODY_TYPE"PLUMBING"
HDL_TAP"TRUE";
"B \NAC \NWC"4;
"S \NAC"
BN"2"44;
%"TAP"
"6","(-3300,4000)","0","mstr_standard","I129";
;
CDS_LIB"mstr_standard"
BODY_TYPE"PLUMBING"
HDL_TAP"TRUE";
"B \NAC \NWC"4;
"S \NAC"
BN"1"54;
%"TAP"
"6","(650,4850)","2","mstr_standard","I13";
;
CDS_LIB"mstr_standard"
BODY_TYPE"PLUMBING"
HDL_TAP"TRUE";
"B \NAC \NWC"1;
"S \NAC"
BN"14"166;
%"TAP"
"6","(-3300,3950)","0","mstr_standard","I130";
;
CDS_LIB"mstr_standard"
BODY_TYPE"PLUMBING"
HDL_TAP"TRUE";
"B \NAC \NWC"4;
"S \NAC"
BN"0"55;
%"TAP"
"6","(-3300,3850)","0","mstr_standard","I131";
;
CDS_LIB"mstr_standard"
BODY_TYPE"PLUMBING"
HDL_TAP"TRUE";
"B \NAC \NWC"9;
"S \NAC"
BN"1"57;
%"TAP"
"6","(-3300,3800)","0","mstr_standard","I132";
;
CDS_LIB"mstr_standard"
BODY_TYPE"PLUMBING"
HDL_TAP"TRUE";
"B \NAC \NWC"9;
"S \NAC"
BN"0"58;
%"TAP"
"6","(-3300,3750)","0","mstr_standard","I134";
;
CDS_LIB"mstr_standard"
BODY_TYPE"PLUMBING"
HDL_TAP"TRUE";
"B \NAC \NWC"8;
"S \NAC"
BN"1"59;
%"TAP"
"6","(-3300,3700)","0","mstr_standard","I135";
;
CDS_LIB"mstr_standard"
BODY_TYPE"PLUMBING"
HDL_TAP"TRUE";
"B \NAC \NWC"8;
"S \NAC"
BN"0"45;
%"TAP"
"6","(-3300,2750)","0","mstr_standard","I137";
;
CDS_LIB"mstr_standard"
BODY_TYPE"PLUMBING"
HDL_TAP"TRUE";
"B \NAC \NWC"10;
"S \NAC"
BN"6"43;
%"TAP"
"6","(650,4950)","2","mstr_standard","I14";
;
CDS_LIB"mstr_standard"
BODY_TYPE"PLUMBING"
HDL_TAP"TRUE";
"B \NAC \NWC"1;
"S \NAC"
BN"15"164;
%"TAP"
"6","(-3300,2700)","0","mstr_standard","I140";
;
CDS_LIB"mstr_standard"
BODY_TYPE"PLUMBING"
HDL_TAP"TRUE";
"B \NAC \NWC"10;
"S \NAC"
BN"7"53;
%"TAP"
"6","(-3300,2650)","0","mstr_standard","I141";
;
CDS_LIB"mstr_standard"
BODY_TYPE"PLUMBING"
HDL_TAP"TRUE";
"B \NAC \NWC"10;
"S \NAC"
BN"4"52;
%"TAP"
"6","(-3300,2600)","0","mstr_standard","I142";
;
CDS_LIB"mstr_standard"
BODY_TYPE"PLUMBING"
HDL_TAP"TRUE";
"B \NAC \NWC"10;
"S \NAC"
BN"5"51;
%"TAP"
"6","(-3300,2550)","0","mstr_standard","I143";
;
CDS_LIB"mstr_standard"
BODY_TYPE"PLUMBING"
HDL_TAP"TRUE";
"B \NAC \NWC"10;
"S \NAC"
BN"2"50;
%"TAP"
"6","(-3300,2500)","0","mstr_standard","I144";
;
CDS_LIB"mstr_standard"
BODY_TYPE"PLUMBING"
HDL_TAP"TRUE";
"B \NAC \NWC"10;
"S \NAC"
BN"3"49;
%"TAP"
"6","(-3300,2400)","0","mstr_standard","I145";
;
CDS_LIB"mstr_standard"
BODY_TYPE"PLUMBING"
HDL_TAP"TRUE";
"B \NAC \NWC"10;
"S \NAC"
BN"1"47;
%"TAP"
"6","(-3300,2450)","0","mstr_standard","I146";
;
CDS_LIB"mstr_standard"
BODY_TYPE"PLUMBING"
HDL_TAP"TRUE";
"B \NAC \NWC"10;
"S \NAC"
BN"0"48;
%"TAP"
"6","(650,4650)","2","mstr_standard","I15";
;
CDS_LIB"mstr_standard"
BODY_TYPE"PLUMBING"
HDL_TAP"TRUE";
"B \NAC \NWC"1;
"S \NAC"
BN"12"170;
%"TAP"
"6","(-3600,3600)","0","mstr_standard","I152";
;
CDS_LIB"mstr_standard"
BODY_TYPE"PLUMBING"
HDL_TAP"TRUE";
"B \NAC \NWC"5;
"S \NAC"
BN"1"65;
%"TAP"
"6","(-3600,3500)","0","mstr_standard","I153";
;
CDS_LIB"mstr_standard"
BODY_TYPE"PLUMBING"
HDL_TAP"TRUE";
"B \NAC \NWC"5;
"S \NAC"
BN"0"63;
%"TAP"
"6","(-3750,3550)","0","mstr_standard","I154";
;
CDS_LIB"mstr_standard"
BODY_TYPE"PLUMBING"
HDL_TAP"TRUE";
"B \NAC \NWC"6;
"S \NAC"
BN"1"64;
%"TAP"
"6","(-3750,3450)","0","mstr_standard","I155";
;
CDS_LIB"mstr_standard"
BODY_TYPE"PLUMBING"
HDL_TAP"TRUE";
"B \NAC \NWC"6;
"S \NAC"
BN"0"62;
%"TAP"
"6","(-3300,3300)","0","mstr_standard","I158";
;
CDS_LIB"mstr_standard"
BODY_TYPE"PLUMBING"
HDL_TAP"TRUE";
"B \NAC \NWC"7;
"S \NAC"
BN"3"61;
%"TAP"
"6","(-3300,3250)","0","mstr_standard","I159";
;
CDS_LIB"mstr_standard"
BODY_TYPE"PLUMBING"
HDL_TAP"TRUE";
"B \NAC \NWC"7;
"S \NAC"
BN"2"60;
%"TAP"
"6","(650,4550)","2","mstr_standard","I16";
;
CDS_LIB"mstr_standard"
BODY_TYPE"PLUMBING"
HDL_TAP"TRUE";
"B \NAC \NWC"1;
"S \NAC"
BN"11"172;
%"TAP"
"6","(-3300,3200)","0","mstr_standard","I160";
;
CDS_LIB"mstr_standard"
BODY_TYPE"PLUMBING"
HDL_TAP"TRUE";
"B \NAC \NWC"7;
"S \NAC"
BN"1"56;
%"TAP"
"6","(-3300,3150)","0","mstr_standard","I161";
;
CDS_LIB"mstr_standard"
BODY_TYPE"PLUMBING"
HDL_TAP"TRUE";
"B \NAC \NWC"7;
"S \NAC"
BN"0"39;
%"TAP"
"6","(-3300,3050)","0","mstr_standard","I162";
;
CDS_LIB"mstr_standard"
BODY_TYPE"PLUMBING"
HDL_TAP"TRUE";
"B \NAC \NWC"11;
"S \NAC"
BN"1"46;
%"TAP"
"6","(-3300,3000)","0","mstr_standard","I163";
;
CDS_LIB"mstr_standard"
BODY_TYPE"PLUMBING"
HDL_TAP"TRUE";
"B \NAC \NWC"11;
"S \NAC"
BN"0"40;
%"TAP"
"6","(-3300,2900)","0","mstr_standard","I164";
;
CDS_LIB"mstr_standard"
BODY_TYPE"PLUMBING"
HDL_TAP"TRUE";
"B \NAC \NWC"12;
"S \NAC"
BN"1"41;
%"TAP"
"6","(-3300,2850)","0","mstr_standard","I168";
;
CDS_LIB"mstr_standard"
BODY_TYPE"PLUMBING"
HDL_TAP"TRUE";
"B \NAC \NWC"12;
"S \NAC"
BN"0"42;
%"SCONN288_H44441004"
"4","(-350,2000)","0","mstr_sconn","I169";
;
CDS_SEC"4"
LOCATION"J1G3"
PART_NUMBER"H44441-004"
MATERIAL"SCONN"
PACK_TYPE"PIP"
BOM_COST"MEM"
CDS_LIB"mstr_sconn"
SEC_TYPE"PIP"
SEC"4"
CDS_LOCATION"J1G3"
ROOM"DDR4_CH_J";
"VPP<4>"
$PN"142"17;
"VTT<1>"
$PN"77"18;
"VPP<0>"
$PN"287"17;
"VPP<1>"
$PN"286"17;
"VPP<2>"
$PN"288"17;
"VPP<3>"
$PN"143"17;
"VDD<1>"
$PN"233"13;
"VDD<2>"
$PN"231"13;
"VDD<3>"
$PN"229"13;
"VDD<4>"
$PN"226"13;
"VDD<5>"
$PN"223"13;
"VDD<7>"
$PN"217"13;
"VDD<8>"
$PN"215"13;
"VDD<9>"
$PN"212"13;
"VDD<11>"
$PN"206"13;
"VDD<12>"
$PN"204"13;
"VDD<14>"
$PN"90"13;
"VDD<15>"
$PN"88"13;
"VDD<17>"
$PN"83"13;
"VDD<18>"
$PN"80"13;
"VDD<20>"
$PN"73"13;
"VDD<21>"
$PN"70"13;
"VDD<22>"
$PN"67"13;
"VDD<24>"
$PN"61"13;
"12V<0>"
$PN"145"20;
"12V<1>"
$PN"1"20;
"VTT<0>"
$PN"221"18;
"VDD<25>"
$PN"59"13;
"VDD<23>"
$PN"64"13;
"VDD<19>"
$PN"76"13;
"VDD<16>"
$PN"85"13;
"VDD<13>"
$PN"92"13;
"VDD<10>"
$PN"209"13;
"VDD<6>"
$PN"220"13;
"VDD<0>"
$PN"236"13;
%"PVDDQ_GHJ"
"1","(-1475,2525)","0","mstr_symbols","I17";
;
VOLTAGE"1.2V"
BOM_COST"MEM"
CDS_LIB"mstr_symbols"
BODY_TYPE"PLUMBING"
ROOM"DDR4_CH_J"
HDL_POWER"PVDDQ_GHJ";
"G\NAC"13;
%"GND"
"1","(2450,1100)","2","mstr_symbols","I170";
;
VOLTAGE"0"
BOM_COST"MEM"
CDS_LIB"mstr_symbols"
SIZE"1B"
BODY_TYPE"PLUMBING"
ROOM"DDR4_CH_J"
HDL_POWER"GND";
"A\NAC"14;
%"GND"
"1","(-5200,1750)","2","mstr_symbols","I175";
;
VOLTAGE"0"
BOM_COST"MEM"
CDS_LIB"mstr_symbols"
SIZE"1B"
BODY_TYPE"PLUMBING"
ROOM"DDR4_CH_J"
HDL_POWER"GND";
"A\NAC"15;
%"GND"
"1","(-4550,1200)","0","mstr_symbols","I177";
;
VOLTAGE"0"
CDS_LIB"mstr_symbols"
SIZE"1B"
BOM_COST"MEM"
BODY_TYPE"PLUMBING"
ROOM"DDR4_CH_J"
HDL_POWER"GND";
"A\NAC"16;
%"CAP_A"
"1","(-4550,1450)","2","dev_discrete","I178";
;
LOCATION"C9U10"
PART_NUMBER"A36096-045"
VALUE"0.01UF"
TOLERANCE"10%"
PACK_TYPE"0402V"
VOLTAGE"25V"
MATERIAL"X7R"
CDS_LOCATION"C9U10"
BOM_COST"MEM"
CDS_LIB"dev_discrete"
CDS_SEC"1"
$SEC"1"
ROOM"DDR4_CH_J";
"B"
$PN"2"16;
"A"
$PN"1"23;
%"PVPP_GHJ"
"1","(-1050,3000)","0","mstr_symbols","I179";
;
VOLTAGE"2.5V"
BOM_COST"MEM"
CDS_LIB"mstr_symbols"
BODY_TYPE"PLUMBING"
ROOM"DDR4_CH_J"
HDL_POWER"PVPP_GHJ";
"G\NAC"17;
%"PVTT_GHJ"
"1","(-1200,2700)","0","mstr_symbols","I18";
;
VOLTAGE"0.6V"
BOM_COST"MEM"
CDS_LIB"mstr_symbols"
BODY_TYPE"PLUMBING"
ROOM"DDR4_CH_J"
HDL_POWER"PVTT_GHJ";
"G\NAC"18;
%"PVPP_GHJ"
"1","(-5200,2150)","0","mstr_symbols","I180";
;
VOLTAGE"2.5V"
BOM_COST"MEM"
CDS_LIB"mstr_symbols"
BODY_TYPE"PLUMBING"
ROOM"DDR4_CH_J"
HDL_POWER"PVPP_GHJ";
"G\NAC"19;
%"SCONN288_H44441004"
"3","(1750,2400)","0","mstr_sconn","I185";
;
CDS_SEC"3"
LOCATION"J1G3"
PART_NUMBER"H44441-004"
MATERIAL"SCONN"
PACK_TYPE"PIP"
BOM_COST"MEM"
CDS_LIB"mstr_sconn"
SEC_TYPE"PIP"
SEC"3"
CDS_LOCATION"J1G3"
ROOM"DDR4_CH_J";
"VSS<93>"
$PN"2"21;
"VSS<92>"
$PN"4"21;
"VSS<91>"
$PN"6"21;
"VSS<90>"
$PN"9"21;
"VSS<89>"
$PN"11"21;
"VSS<88>"
$PN"13"21;
"VSS<0>"
$PN"283"14;
"VSS<1>"
$PN"281"14;
"VSS<2>"
$PN"279"14;
"VSS<3>"
$PN"276"14;
"VSS<4>"
$PN"274"14;
"VSS<5>"
$PN"272"14;
"VSS<6>"
$PN"270"14;
"VSS<7>"
$PN"268"14;
"VSS<8>"
$PN"265"14;
"VSS<9>"
$PN"263"14;
"VSS<10>"
$PN"261"14;
"VSS<11>"
$PN"259"14;
"VSS<12>"
$PN"257"14;
"VSS<13>"
$PN"254"14;
"VSS<14>"
$PN"252"14;
"VSS<15>"
$PN"250"14;
"VSS<16>"
$PN"248"14;
"VSS<17>"
$PN"246"14;
"VSS<18>"
$PN"243"14;
"VSS<19>"
$PN"241"14;
"VSS<20>"
$PN"239"14;
"VSS<21>"
$PN"202"14;
"VSS<22>"
$PN"200"14;
"VSS<23>"
$PN"198"14;
"VSS<24>"
$PN"195"14;
"VSS<25>"
$PN"193"14;
"VSS<26>"
$PN"191"14;
"VSS<27>"
$PN"189"14;
"VSS<28>"
$PN"187"14;
"VSS<29>"
$PN"184"14;
"VSS<30>"
$PN"182"14;
"VSS<31>"
$PN"180"14;
"VSS<32>"
$PN"178"14;
"VSS<33>"
$PN"176"14;
"VSS<34>"
$PN"173"14;
"VSS<35>"
$PN"171"14;
"VSS<36>"
$PN"169"14;
"VSS<37>"
$PN"167"14;
"VSS<38>"
$PN"165"14;
"VSS<39>"
$PN"162"14;
"VSS<40>"
$PN"160"14;
"VSS<41>"
$PN"158"14;
"VSS<42>"
$PN"156"14;
"VSS<43>"
$PN"154"14;
"VSS<44>"
$PN"151"14;
"VSS<47>"
$PN"138"21;
"VSS<48>"
$PN"136"21;
"VSS<49>"
$PN"134"21;
"VSS<50>"
$PN"131"21;
"VSS<51>"
$PN"129"21;
"VSS<52>"
$PN"127"21;
"VSS<53>"
$PN"125"21;
"VSS<54>"
$PN"123"21;
"VSS<55>"
$PN"120"21;
"VSS<56>"
$PN"118"21;
"VSS<57>"
$PN"116"21;
"VSS<58>"
$PN"114"21;
"VSS<59>"
$PN"112"21;
"VSS<60>"
$PN"109"21;
"VSS<61>"
$PN"107"21;
"VSS<62>"
$PN"105"21;
"VSS<63>"
$PN"103"21;
"VSS<64>"
$PN"101"21;
"VSS<65>"
$PN"98"21;
"VSS<66>"
$PN"96"21;
"VSS<67>"
$PN"94"21;
"VSS<68>"
$PN"57"21;
"VSS<69>"
$PN"55"21;
"VSS<70>"
$PN"53"21;
"VSS<71>"
$PN"50"21;
"VSS<72>"
$PN"48"21;
"VSS<73>"
$PN"46"21;
"VSS<74>"
$PN"44"21;
"VSS<75>"
$PN"42"21;
"VSS<76>"
$PN"39"21;
"VSS<77>"
$PN"37"21;
"VSS<78>"
$PN"35"21;
"VSS<79>"
$PN"33"21;
"VSS<80>"
$PN"31"21;
"VSS<81>"
$PN"28"21;
"VSS<82>"
$PN"26"21;
"VSS<83>"
$PN"24"21;
"VSS<84>"
$PN"22"21;
"VSS<85>"
$PN"20"21;
"VSS<86>"
$PN"17"21;
"VSS<87>"
$PN"15"21;
"VSS<45>"
$PN"149"14;
"VSS<46>"
$PN"147"14;
%"SCONN288_H44441004"
"1","(-2550,3150)","0","mstr_sconn","I186";
;
CDS_SEC"1"
LOCATION"J1G3"
PART_NUMBER"H44441-004"
MATERIAL"SCONN"
PACK_TYPE"PIP"
BOM_COST"MEM"
CDS_LIB"mstr_sconn"
SEC_TYPE"PIP"
SEC"1"
CDS_LOCATION"J1G3"
ROOM"DDR4_CH_J";
"DQ<63>"
$PN"280"130;
"DQ<62>"
$PN"135"131;
"DQ<61>"
$PN"273"132;
"DQ<5>"
$PN"148"67;
"DQ<4>"
$PN"3"68;
"DQ<3>"
$PN"157"69;
"DQ<2>"
$PN"12"70;
"DQ<47>"
$PN"258"71;
"DQ<48>"
$PN"119"72;
"DQ<49>"
$PN"264"133;
"DQ<50>"
$PN"126"134;
"DQ<51>"
$PN"271"135;
"DQ<52>"
$PN"117"136;
"DQ<53>"
$PN"262"137;
"DQ<54>"
$PN"124"138;
"DQ<58>"
$PN"137"139;
"DQ<57>"
$PN"275"140;
"SAVE_N_NC"
$PN"230"35;
"RFU<1>"
$PN"227"30;
"RFU<0>"
$PN"205"31;
"DQ<17>"
$PN"172"114;
"DQ<15>"
$PN"166"73;
"DQ<26>"
$PN"45"74;
"DQ<27>"
$PN"190"75;
"S0_N"
$PN"84"39;
"CKE<0>"
$PN"60"40;
"ODT<1>"
$PN"91"41;
"ODT<0>"
$PN"87"42;
"CB<7>"
$PN"199"43;
"A16_RAS_N"
$PN"82"115;
"A15_CAS_N"
$PN"86"116;
"A14_WE_N"
$PN"228"117;
"A11"
$PN"210"118;
"A10"
$PN"225"119;
"DQ<38>"
$PN"102"76;
"DQ<36>"
$PN"95"77;
"DQ<35>"
$PN"249"78;
"A2"
$PN"216"44;
"ALERT_N"
$PN"208"66;
"ACT_N"
$PN"62"28;
"DQ<0>"
$PN"5"79;
"DQ<1>"
$PN"150"80;
"SA<1>"
$PN"140"15;
"SA<2>"
$PN"238"19;
"VDDSPD"
$PN"284"19;
"SA<0>"
$PN"139"15;
"BA<0>"
$PN"81"58;
"BG<1>"
$PN"207"59;
"BG<0>"
$PN"63"45;
"CK1P"
$PN"218"65;
"VREFCA"
$PN"146"23;
"SDA"
$PN"285"34;
"SCL"
$PN"141"33;
"RFU<2>"
$PN"144"32;
"RESET_N"
$PN"58"36;
"PAR"
$PN"222"37;
"EVENT_N"
$PN"78"29;
"DQ<6>"
$PN"10"81;
"DQ<7>"
$PN"155"82;
"DQ<8>"
$PN"16"83;
"DQ<9>"
$PN"161"84;
"DQ<10>"
$PN"23"113;
"DQ<11>"
$PN"168"85;
"DQ<12>"
$PN"14"86;
"DQ<13>"
$PN"159"87;
"DQ<14>"
$PN"21"88;
"DQ<16>"
$PN"27"89;
"DQ<18>"
$PN"34"90;
"DQ<19>"
$PN"179"91;
"DQ<20>"
$PN"25"92;
"DQ<21>"
$PN"170"93;
"DQ<22>"
$PN"32"94;
"DQ<23>"
$PN"177"95;
"DQ<24>"
$PN"38"96;
"DQ<25>"
$PN"183"27;
"DQ<30>"
$PN"43"97;
"DQ<31>"
$PN"188"98;
"DQ<32>"
$PN"97"99;
"DQ<33>"
$PN"242"100;
"DQ<34>"
$PN"104"101;
"DQ<37>"
$PN"240"102;
"DQ<39>"
$PN"247"103;
"DQ<40>"
$PN"108"104;
"DQ<41>"
$PN"253"105;
"DQ<42>"
$PN"115"106;
"DQ<43>"
$PN"260"107;
"DQ<44>"
$PN"106"108;
"DQ<45>"
$PN"251"109;
"DQ<46>"
$PN"113"110;
"DQ<55>"
$PN"269"141;
"DQ<56>"
$PN"130"142;
"DQ<59>"
$PN"282"143;
"DQ<60>"
$PN"128"144;
"CKE<1>"
$PN"203"46;
"CK0N"
$PN"75"62;
"CB<0>"
$PN"49"47;
"CB<1>"
$PN"194"48;
"CB<2>"
$PN"56"49;
"CB<3>"
$PN"201"50;
"CB<4>"
$PN"47"51;
"CB<5>"
$PN"192"52;
"CB<6>"
$PN"54"53;
"A9"
$PN"66"120;
"A8"
$PN"68"121;
"A7"
$PN"211"122;
"A6"
$PN"69"123;
"A5"
$PN"213"124;
"A4"
$PN"214"125;
"A3"
$PN"71"126;
"A17"
$PN"234"127;
"A13"
$PN"232"128;
"A12"
$PN"65"129;
"A1"
$PN"72"54;
"A0"
$PN"79"55;
"C<2>"
$PN"235"38;
"DQ<28>"
$PN"36"111;
"DQ<29>"
$PN"181"112;
"S1_N"
$PN"89"56;
"S2_N_C<0>"
$PN"93"60;
"S3_N_C<1>"
$PN"237"61;
"CK0P"
$PN"74"63;
"CK1N"
$PN"219"64;
"BA<1>"
$PN"224"57;
%"P12V_NVDIMM_GHJ"
"1","(350,2975)","0","mstr_symbols","I187";
;
VOLTAGE"12.0"
CDS_LIB"mstr_symbols"
BODY_TYPE"PLUMBING"
HDL_POWER"P12V_NVDIMM_GHJ";
"G\NAC"20;
%"TAP"
"6","(850,4300)","2","mstr_standard","I20";
;
CDS_LIB"mstr_standard"
BODY_TYPE"PLUMBING"
HDL_TAP"TRUE";
"B \NAC \NWC"2;
"S \NAC"
BN"9"24;
%"TAP"
"6","(850,4400)","2","mstr_standard","I21";
;
CDS_LIB"mstr_standard"
BODY_TYPE"PLUMBING"
HDL_TAP"TRUE";
"B \NAC \NWC"2;
"S \NAC"
BN"10"175;
%"TAP"
"6","(850,4200)","2","mstr_standard","I22";
;
CDS_LIB"mstr_standard"
BODY_TYPE"PLUMBING"
HDL_TAP"TRUE";
"B \NAC \NWC"2;
"S \NAC"
BN"8"26;
%"TAP"
"6","(850,4100)","2","mstr_standard","I23";
;
CDS_LIB"mstr_standard"
BODY_TYPE"PLUMBING"
HDL_TAP"TRUE";
"B \NAC \NWC"2;
"S \NAC"
BN"7"160;
%"TAP"
"6","(850,4000)","2","mstr_standard","I24";
;
CDS_LIB"mstr_standard"
BODY_TYPE"PLUMBING"
HDL_TAP"TRUE";
"B \NAC \NWC"2;
"S \NAC"
BN"6"146;
%"TAP"
"6","(650,4250)","2","mstr_standard","I25";
;
CDS_LIB"mstr_standard"
BODY_TYPE"PLUMBING"
HDL_TAP"TRUE";
"B \NAC \NWC"1;
"S \NAC"
BN"8"25;
%"TAP"
"6","(650,4350)","2","mstr_standard","I26";
;
CDS_LIB"mstr_standard"
BODY_TYPE"PLUMBING"
HDL_TAP"TRUE";
"B \NAC \NWC"1;
"S \NAC"
BN"9"158;
%"TAP"
"6","(650,4450)","2","mstr_standard","I27";
;
CDS_LIB"mstr_standard"
BODY_TYPE"PLUMBING"
HDL_TAP"TRUE";
"B \NAC \NWC"1;
"S \NAC"
BN"10"174;
%"TAP"
"6","(650,4150)","2","mstr_standard","I28";
;
CDS_LIB"mstr_standard"
BODY_TYPE"PLUMBING"
HDL_TAP"TRUE";
"B \NAC \NWC"1;
"S \NAC"
BN"7"159;
%"TAP"
"6","(650,4050)","2","mstr_standard","I29";
;
CDS_LIB"mstr_standard"
BODY_TYPE"PLUMBING"
HDL_TAP"TRUE";
"B \NAC \NWC"1;
"S \NAC"
BN"6"145;
%"TAP"
"6","(850,5100)","2","mstr_standard","I3";
;
CDS_LIB"mstr_standard"
BODY_TYPE"PLUMBING"
HDL_TAP"TRUE";
"B \NAC \NWC"2;
"S \NAC"
BN"17"161;
%"TAP"
"6","(850,3900)","2","mstr_standard","I30";
;
CDS_LIB"mstr_standard"
BODY_TYPE"PLUMBING"
HDL_TAP"TRUE";
"B \NAC \NWC"2;
"S \NAC"
BN"5"148;
%"TAP"
"6","(850,3800)","2","mstr_standard","I31";
;
CDS_LIB"mstr_standard"
BODY_TYPE"PLUMBING"
HDL_TAP"TRUE";
"B \NAC \NWC"2;
"S \NAC"
BN"4"150;
%"TAP"
"6","(850,3700)","2","mstr_standard","I32";
;
CDS_LIB"mstr_standard"
BODY_TYPE"PLUMBING"
HDL_TAP"TRUE";
"B \NAC \NWC"2;
"S \NAC"
BN"3"151;
%"TAP"
"6","(850,3600)","2","mstr_standard","I33";
;
CDS_LIB"mstr_standard"
BODY_TYPE"PLUMBING"
HDL_TAP"TRUE";
"B \NAC \NWC"2;
"S \NAC"
BN"2"153;
%"TAP"
"6","(850,3500)","2","mstr_standard","I34";
;
CDS_LIB"mstr_standard"
BODY_TYPE"PLUMBING"
HDL_TAP"TRUE";
"B \NAC \NWC"2;
"S \NAC"
BN"1"155;
%"TAP"
"6","(650,3750)","2","mstr_standard","I35";
;
CDS_LIB"mstr_standard"
BODY_TYPE"PLUMBING"
HDL_TAP"TRUE";
"B \NAC \NWC"1;
"S \NAC"
BN"3"22;
%"TAP"
"6","(650,3850)","2","mstr_standard","I36";
;
CDS_LIB"mstr_standard"
BODY_TYPE"PLUMBING"
HDL_TAP"TRUE";
"B \NAC \NWC"1;
"S \NAC"
BN"4"149;
%"TAP"
"6","(650,3950)","2","mstr_standard","I37";
;
CDS_LIB"mstr_standard"
BODY_TYPE"PLUMBING"
HDL_TAP"TRUE";
"B \NAC \NWC"1;
"S \NAC"
BN"5"147;
%"TAP"
"6","(650,3550)","2","mstr_standard","I38";
;
CDS_LIB"mstr_standard"
BODY_TYPE"PLUMBING"
HDL_TAP"TRUE";
"B \NAC \NWC"1;
"S \NAC"
BN"1"154;
%"TAP"
"6","(650,3450)","2","mstr_standard","I39";
;
CDS_LIB"mstr_standard"
BODY_TYPE"PLUMBING"
HDL_TAP"TRUE";
"B \NAC \NWC"1;
"S \NAC"
BN"0"156;
%"TAP"
"6","(850,5000)","2","mstr_standard","I4";
;
CDS_LIB"mstr_standard"
BODY_TYPE"PLUMBING"
HDL_TAP"TRUE";
"B \NAC \NWC"2;
"S \NAC"
BN"16"163;
%"TAP"
"6","(650,3650)","2","mstr_standard","I40";
;
CDS_LIB"mstr_standard"
BODY_TYPE"PLUMBING"
HDL_TAP"TRUE";
"B \NAC \NWC"1;
"S \NAC"
BN"2"152;
%"TAP"
"6","(850,3400)","2","mstr_standard","I41";
;
CDS_LIB"mstr_standard"
BODY_TYPE"PLUMBING"
HDL_TAP"TRUE";
"B \NAC \NWC"2;
"S \NAC"
BN"0"157;
%"GND"
"1","(1050,1100)","2","mstr_symbols","I44";
;
VOLTAGE"0"
BOM_COST"MEM"
CDS_LIB"mstr_symbols"
SIZE"1B"
BODY_TYPE"PLUMBING"
ROOM"DDR4_CH_J"
HDL_POWER"GND";
"A\NAC"21;
%"TAP"
"6","(-1800,4800)","2","mstr_standard","I46";
;
CDS_LIB"mstr_standard"
BODY_TYPE"PLUMBING"
HDL_TAP"TRUE";
"B \NAC \NWC"3;
"S \NAC"
BN"62"130;
%"TAP"
"6","(-1800,4550)","2","mstr_standard","I47";
;
CDS_LIB"mstr_standard"
BODY_TYPE"PLUMBING"
HDL_TAP"TRUE";
"B \NAC \NWC"3;
"S \NAC"
BN"59"139;
%"TAP"
"6","(-1800,4600)","2","mstr_standard","I48";
;
CDS_LIB"mstr_standard"
BODY_TYPE"PLUMBING"
HDL_TAP"TRUE";
"B \NAC \NWC"3;
"S \NAC"
BN"58"143;
%"TAP"
"6","(-1800,4700)","2","mstr_standard","I49";
;
CDS_LIB"mstr_standard"
BODY_TYPE"PLUMBING"
HDL_TAP"TRUE";
"B \NAC \NWC"3;
"S \NAC"
BN"60"132;
%"TAP"
"6","(650,5150)","2","mstr_standard","I5";
;
CDS_LIB"mstr_standard"
BODY_TYPE"PLUMBING"
HDL_TAP"TRUE";
"B \NAC \NWC"1;
"S \NAC"
BN"17"176;
%"TAP"
"6","(-1800,4650)","2","mstr_standard","I50";
;
CDS_LIB"mstr_standard"
BODY_TYPE"PLUMBING"
HDL_TAP"TRUE";
"B \NAC \NWC"3;
"S \NAC"
BN"61"144;
%"TAP"
"6","(-1800,4750)","2","mstr_standard","I51";
;
CDS_LIB"mstr_standard"
BODY_TYPE"PLUMBING"
HDL_TAP"TRUE";
"B \NAC \NWC"3;
"S \NAC"
BN"63"131;
%"TAP"
"6","(-1800,4450)","2","mstr_standard","I52";
;
CDS_LIB"mstr_standard"
BODY_TYPE"PLUMBING"
HDL_TAP"TRUE";
"B \NAC \NWC"3;
"S \NAC"
BN"57"142;
%"TAP"
"6","(-1800,4400)","2","mstr_standard","I53";
;
CDS_LIB"mstr_standard"
BODY_TYPE"PLUMBING"
HDL_TAP"TRUE";
"B \NAC \NWC"3;
"S \NAC"
BN"54"141;
%"TAP"
"6","(-1800,4350)","2","mstr_standard","I54";
;
CDS_LIB"mstr_standard"
BODY_TYPE"PLUMBING"
HDL_TAP"TRUE";
"B \NAC \NWC"3;
"S \NAC"
BN"55"138;
%"TAP"
"6","(-1800,4300)","2","mstr_standard","I55";
;
CDS_LIB"mstr_standard"
BODY_TYPE"PLUMBING"
HDL_TAP"TRUE";
"B \NAC \NWC"3;
"S \NAC"
BN"52"137;
%"TAP"
"6","(-1800,4500)","2","mstr_standard","I56";
;
CDS_LIB"mstr_standard"
BODY_TYPE"PLUMBING"
HDL_TAP"TRUE";
"B \NAC \NWC"3;
"S \NAC"
BN"56"140;
%"TAP"
"6","(-1800,4200)","2","mstr_standard","I57";
;
CDS_LIB"mstr_standard"
BODY_TYPE"PLUMBING"
HDL_TAP"TRUE";
"B \NAC \NWC"3;
"S \NAC"
BN"50"135;
%"TAP"
"6","(-1800,4150)","2","mstr_standard","I58";
;
CDS_LIB"mstr_standard"
BODY_TYPE"PLUMBING"
HDL_TAP"TRUE";
"B \NAC \NWC"3;
"S \NAC"
BN"51"134;
%"TAP"
"6","(-1800,4100)","2","mstr_standard","I59";
;
CDS_LIB"mstr_standard"
BODY_TYPE"PLUMBING"
HDL_TAP"TRUE";
"B \NAC \NWC"3;
"S \NAC"
BN"48"133;
%"TAP"
"6","(650,5050)","2","mstr_standard","I6";
;
CDS_LIB"mstr_standard"
BODY_TYPE"PLUMBING"
HDL_TAP"TRUE";
"B \NAC \NWC"1;
"S \NAC"
BN"16"162;
%"TAP"
"6","(-1800,4050)","2","mstr_standard","I60";
;
CDS_LIB"mstr_standard"
BODY_TYPE"PLUMBING"
HDL_TAP"TRUE";
"B \NAC \NWC"3;
"S \NAC"
BN"49"72;
%"TAP"
"6","(-1800,4250)","2","mstr_standard","I61";
;
CDS_LIB"mstr_standard"
BODY_TYPE"PLUMBING"
HDL_TAP"TRUE";
"B \NAC \NWC"3;
"S \NAC"
BN"53"136;
%"TAP"
"6","(-1800,3900)","2","mstr_standard","I62";
;
CDS_LIB"mstr_standard"
BODY_TYPE"PLUMBING"
HDL_TAP"TRUE";
"B \NAC \NWC"3;
"S \NAC"
BN"44"109;
%"TAP"
"6","(-1800,3850)","2","mstr_standard","I63";
;
CDS_LIB"mstr_standard"
BODY_TYPE"PLUMBING"
HDL_TAP"TRUE";
"B \NAC \NWC"3;
"S \NAC"
BN"45"108;
%"TAP"
"6","(-1800,3800)","2","mstr_standard","I64";
;
CDS_LIB"mstr_standard"
BODY_TYPE"PLUMBING"
HDL_TAP"TRUE";
"B \NAC \NWC"3;
"S \NAC"
BN"42"107;
%"TAP"
"6","(-1800,3950)","2","mstr_standard","I65";
;
CDS_LIB"mstr_standard"
BODY_TYPE"PLUMBING"
HDL_TAP"TRUE";
"B \NAC \NWC"3;
"S \NAC"
BN"47"110;
%"TAP"
"6","(-1800,4000)","2","mstr_standard","I66";
;
CDS_LIB"mstr_standard"
BODY_TYPE"PLUMBING"
HDL_TAP"TRUE";
"B \NAC \NWC"3;
"S \NAC"
BN"46"71;
%"SCONN288_H44441004"
"2","(-50,4300)","0","mstr_sconn","I67";
;
CDS_SEC"2"
LOCATION"J1G3"
PART_NUMBER"H44441-004"
MATERIAL"SCONN"
PACK_TYPE"PIP"
BOM_COST"MEM"
CDS_LIB"mstr_sconn"
SEC_TYPE"PIP"
SEC"2"
CDS_LOCATION"J1G3"
ROOM"DDR4_CH_J";
"DQS17P"
$PN"51"176;
"DQS9P"
$PN"7"158;
"DQS9N"
$PN"8"24;
"DQS8P"
$PN"197"25;
"DQS8N"
$PN"196"26;
"DQS7P"
$PN"278"159;
"DQS7N"
$PN"277"160;
"DQS6P"
$PN"267"145;
"DQS6N"
$PN"266"146;
"DQS5P"
$PN"256"147;
"DQS5N"
$PN"255"148;
"DQS4P"
$PN"245"149;
"DQS4N"
$PN"244"150;
"DQS3P"
$PN"186"22;
"DQS3N"
$PN"185"151;
"DQS2P"
$PN"175"152;
"DQS2N"
$PN"174"153;
"DQS1P"
$PN"164"154;
"DQS1N"
$PN"163"155;
"DQS17N"
$PN"52"161;
"DQS16P"
$PN"132"162;
"DQS16N"
$PN"133"163;
"DQS15P"
$PN"121"164;
"DQS15N"
$PN"122"165;
"DQS14P"
$PN"110"166;
"DQS14N"
$PN"111"167;
"DQS13P"
$PN"99"168;
"DQS13N"
$PN"100"169;
"DQS12P"
$PN"40"170;
"DQS12N"
$PN"41"171;
"DQS11P"
$PN"29"172;
"DQS11N"
$PN"30"173;
"DQS10P"
$PN"18"174;
"DQS10N"
$PN"19"175;
"DQS0P"
$PN"153"156;
"DQS0N"
$PN"152"157;
%"TAP"
"6","(-1800,3600)","2","mstr_standard","I68";
;
CDS_LIB"mstr_standard"
BODY_TYPE"PLUMBING"
HDL_TAP"TRUE";
"B \NAC \NWC"3;
"S \NAC"
BN"38"103;
%"TAP"
"6","(-1800,3650)","2","mstr_standard","I69";
;
CDS_LIB"mstr_standard"
BODY_TYPE"PLUMBING"
HDL_TAP"TRUE";
"B \NAC \NWC"3;
"S \NAC"
BN"41"104;
%"TAP"
"6","(850,4800)","2","mstr_standard","I7";
;
CDS_LIB"mstr_standard"
BODY_TYPE"PLUMBING"
HDL_TAP"TRUE";
"B \NAC \NWC"2;
"S \NAC"
BN"14"167;
%"TAP"
"6","(-1800,3550)","2","mstr_standard","I70";
;
CDS_LIB"mstr_standard"
BODY_TYPE"PLUMBING"
HDL_TAP"TRUE";
"B \NAC \NWC"3;
"S \NAC"
BN"39"76;
%"TAP"
"6","(-1800,3700)","2","mstr_standard","I71";
;
CDS_LIB"mstr_standard"
BODY_TYPE"PLUMBING"
HDL_TAP"TRUE";
"B \NAC \NWC"3;
"S \NAC"
BN"40"105;
%"TAP"
"6","(-1800,3750)","2","mstr_standard","I72";
;
CDS_LIB"mstr_standard"
BODY_TYPE"PLUMBING"
HDL_TAP"TRUE";
"B \NAC \NWC"3;
"S \NAC"
BN"43"106;
%"TAP"
"6","(-1800,3350)","2","mstr_standard","I73";
;
CDS_LIB"mstr_standard"
BODY_TYPE"PLUMBING"
HDL_TAP"TRUE";
"B \NAC \NWC"3;
"S \NAC"
BN"35"101;
%"TAP"
"6","(-1800,3400)","2","mstr_standard","I74";
;
CDS_LIB"mstr_standard"
BODY_TYPE"PLUMBING"
HDL_TAP"TRUE";
"B \NAC \NWC"3;
"S \NAC"
BN"34"78;
%"TAP"
"6","(-1800,3300)","2","mstr_standard","I75";
;
CDS_LIB"mstr_standard"
BODY_TYPE"PLUMBING"
HDL_TAP"TRUE";
"B \NAC \NWC"3;
"S \NAC"
BN"32"100;
%"TAP"
"6","(-1800,3450)","2","mstr_standard","I76";
;
CDS_LIB"mstr_standard"
BODY_TYPE"PLUMBING"
HDL_TAP"TRUE";
"B \NAC \NWC"3;
"S \NAC"
BN"37"77;
%"TAP"
"6","(-1800,3500)","2","mstr_standard","I77";
;
CDS_LIB"mstr_standard"
BODY_TYPE"PLUMBING"
HDL_TAP"TRUE";
"B \NAC \NWC"3;
"S \NAC"
BN"36"102;
%"TAP"
"6","(-1800,3150)","2","mstr_standard","I78";
;
CDS_LIB"mstr_standard"
BODY_TYPE"PLUMBING"
HDL_TAP"TRUE";
"B \NAC \NWC"3;
"S \NAC"
BN"31"97;
%"TAP"
"6","(-1800,3100)","2","mstr_standard","I79";
;
CDS_LIB"mstr_standard"
BODY_TYPE"PLUMBING"
HDL_TAP"TRUE";
"B \NAC \NWC"3;
"S \NAC"
BN"28"112;
%"TAP"
"6","(850,4900)","2","mstr_standard","I8";
;
CDS_LIB"mstr_standard"
BODY_TYPE"PLUMBING"
HDL_TAP"TRUE";
"B \NAC \NWC"2;
"S \NAC"
BN"15"165;
%"TAP"
"6","(-1800,3050)","2","mstr_standard","I80";
;
CDS_LIB"mstr_standard"
BODY_TYPE"PLUMBING"
HDL_TAP"TRUE";
"B \NAC \NWC"3;
"S \NAC"
BN"29"111;
%"TAP"
"6","(-1800,3200)","2","mstr_standard","I81";
;
CDS_LIB"mstr_standard"
BODY_TYPE"PLUMBING"
HDL_TAP"TRUE";
"B \NAC \NWC"3;
"S \NAC"
BN"30"98;
%"TAP"
"6","(-1800,3250)","2","mstr_standard","I82";
;
CDS_LIB"mstr_standard"
BODY_TYPE"PLUMBING"
HDL_TAP"TRUE";
"B \NAC \NWC"3;
"S \NAC"
BN"33"99;
%"TAP"
"6","(-1800,2850)","2","mstr_standard","I83";
;
CDS_LIB"mstr_standard"
BODY_TYPE"PLUMBING"
HDL_TAP"TRUE";
"B \NAC \NWC"3;
"S \NAC"
BN"25"96;
%"TAP"
"6","(-1800,2900)","2","mstr_standard","I84";
;
CDS_LIB"mstr_standard"
BODY_TYPE"PLUMBING"
HDL_TAP"TRUE";
"B \NAC \NWC"3;
"S \NAC"
BN"24"27;
%"TAP"
"6","(-1800,2800)","2","mstr_standard","I85";
;
CDS_LIB"mstr_standard"
BODY_TYPE"PLUMBING"
HDL_TAP"TRUE";
"B \NAC \NWC"3;
"S \NAC"
BN"22"95;
%"TAP"
"6","(-1800,2750)","2","mstr_standard","I86";
;
CDS_LIB"mstr_standard"
BODY_TYPE"PLUMBING"
HDL_TAP"TRUE";
"B \NAC \NWC"3;
"S \NAC"
BN"23"94;
%"TAP"
"6","(-1800,2950)","2","mstr_standard","I87";
;
CDS_LIB"mstr_standard"
BODY_TYPE"PLUMBING"
HDL_TAP"TRUE";
"B \NAC \NWC"3;
"S \NAC"
BN"27"74;
%"TAP"
"6","(-1800,3000)","2","mstr_standard","I88";
;
CDS_LIB"mstr_standard"
BODY_TYPE"PLUMBING"
HDL_TAP"TRUE";
"B \NAC \NWC"3;
"S \NAC"
BN"26"75;
%"TAP"
"6","(-1800,2650)","2","mstr_standard","I89";
;
CDS_LIB"mstr_standard"
BODY_TYPE"PLUMBING"
HDL_TAP"TRUE";
"B \NAC \NWC"3;
"S \NAC"
BN"21"92;
%"TAP"
"6","(850,4600)","2","mstr_standard","I9";
;
CDS_LIB"mstr_standard"
BODY_TYPE"PLUMBING"
HDL_TAP"TRUE";
"B \NAC \NWC"2;
"S \NAC"
BN"12"171;
%"TAP"
"6","(-1800,2600)","2","mstr_standard","I90";
;
CDS_LIB"mstr_standard"
BODY_TYPE"PLUMBING"
HDL_TAP"TRUE";
"B \NAC \NWC"3;
"S \NAC"
BN"18"91;
%"TAP"
"6","(-1800,2550)","2","mstr_standard","I91";
;
CDS_LIB"mstr_standard"
BODY_TYPE"PLUMBING"
HDL_TAP"TRUE";
"B \NAC \NWC"3;
"S \NAC"
BN"19"90;
%"TAP"
"6","(-1800,2500)","2","mstr_standard","I92";
;
CDS_LIB"mstr_standard"
BODY_TYPE"PLUMBING"
HDL_TAP"TRUE";
"B \NAC \NWC"3;
"S \NAC"
BN"16"114;
%"TAP"
"6","(-1800,2700)","2","mstr_standard","I93";
;
CDS_LIB"mstr_standard"
BODY_TYPE"PLUMBING"
HDL_TAP"TRUE";
"B \NAC \NWC"3;
"S \NAC"
BN"20"93;
%"TAP"
"6","(-1800,2400)","2","mstr_standard","I94";
;
CDS_LIB"mstr_standard"
BODY_TYPE"PLUMBING"
HDL_TAP"TRUE";
"B \NAC \NWC"3;
"S \NAC"
BN"14"73;
%"TAP"
"6","(-1800,2350)","2","mstr_standard","I95";
;
CDS_LIB"mstr_standard"
BODY_TYPE"PLUMBING"
HDL_TAP"TRUE";
"B \NAC \NWC"3;
"S \NAC"
BN"15"88;
%"TAP"
"6","(-1800,2250)","2","mstr_standard","I96";
;
CDS_LIB"mstr_standard"
BODY_TYPE"PLUMBING"
HDL_TAP"TRUE";
"B \NAC \NWC"3;
"S \NAC"
BN"13"86;
%"TAP"
"6","(-1800,2300)","2","mstr_standard","I97";
;
CDS_LIB"mstr_standard"
BODY_TYPE"PLUMBING"
HDL_TAP"TRUE";
"B \NAC \NWC"3;
"S \NAC"
BN"12"87;
%"TAP"
"6","(-1800,2450)","2","mstr_standard","I98";
;
CDS_LIB"mstr_standard"
BODY_TYPE"PLUMBING"
HDL_TAP"TRUE";
"B \NAC \NWC"3;
"S \NAC"
BN"17"89;
%"TAP"
"6","(-1800,2200)","2","mstr_standard","I99";
;
CDS_LIB"mstr_standard"
BODY_TYPE"PLUMBING"
HDL_TAP"TRUE";
"B \NAC \NWC"3;
"S \NAC"
BN"10"85;
END.
